# BASEBOARD_FAB2 (Tioga Pass) — schematic netlist excerpt (pin names and nets, part order shuffled) for the footprints in the layout excerpt that follows; sources: Cadence DE-HDL packaged netlist, KiCad conversion of Wiwynn_Tioga_Pass_MB.brd

C25W40  CAP  1.0UF 16V 10% X6S  pkg 0402  page 149 : A = VCC_D_3V3 ; B = GND
R9N4  RES  51.1 1.0% CHIP  pkg 0402  page 210 : A = PVSA_CPU1 ; B = GND
C3P2  CAP_A  0.1UF 16V 10% X7R  pkg 0402V  page 211 : A = VR_PVCCIO_CPU0_VINSEN ; B = GND

(kicad_pcb
	(version 20260206)
	(generator "pcbnew")
	(generator_version "10.0")
	(general
		(thickness 1.6)
		(legacy_teardrops no)
	)
	(paper "A4")
	(title_block
		(title "Wiwynn_Tioga_Pass_MB.brd")
		(comment 1 "Tioga Pass / footprints 3270-3272 of 4770")
	)
	(layers
		(0 "F.Cu" signal "TOP")
		(4 "In1.Cu" signal "L2GND")
		(6 "In2.Cu" signal "L3")
		(8 "In3.Cu" signal "L4GND")
		(10 "In4.Cu" signal "L5")
		(12 "In5.Cu" signal "L6GND")
		(14 "In6.Cu" signal "L7VCC")
		(16 "In7.Cu" signal "L8VCC")
		(18 "In8.Cu" signal "L9GND")
		(20 "In9.Cu" signal "L10")
		(22 "In10.Cu" signal "L11GND")
		(24 "In11.Cu" signal "L12")
		(26 "In12.Cu" signal "L13GND")
		(2 "B.Cu" signal "BOTTOM")
		(9 "F.Adhes" user "F.Adhesive")
		(11 "B.Adhes" user "B.Adhesive")
		(13 "F.Paste" user "Package Geometry/Pastemask Top")
		(15 "B.Paste" user "Package Geometry/Pastemask Bottom")
		(5 "F.SilkS" user "Ref Des/Silkscreen Top")
		(7 "B.SilkS" user "Ref Des/Silkscreen Bottom")
		(1 "F.Mask" user "Board Geometry/Soldermask Top")
		(3 "B.Mask" user "Board Geometry/Soldermask Bottom")
		(17 "Dwgs.User" user "User.Drawings")
		(19 "Cmts.User" user "User.Comments")
		(21 "Eco1.User" user "User.Eco1")
		(23 "Eco2.User" user "User.Eco2")
		(25 "Edge.Cuts" user "Board Geometry/Outline")
		(27 "Margin" user)
		(31 "F.CrtYd" user "Package Geometry/Place Bound Top")
		(29 "B.CrtYd" user "Package Geometry/Place Bound Bottom")
		(35 "F.Fab" user "Ref Des/Assembly Top")
		(33 "B.Fab" user "Ref Des/Assembly Bottom")
	)
	(footprint ""
		(layer "B.Cu")
		(at 414.75152 -45.576744 -90)
		(property "Reference" "C25W40"
			(at 0.8382 -0.67818 270)
			(unlocked yes)
			(layer "B.SilkS")
			(effects
				(font
					(size 0.4064 0.254)
					(thickness 0.1524)
				)
				(justify left mirror)
			)
		)
		(property "Value" ""
			(at 0 0 90)
			(layer "B.Fab")
			(effects
				(font
					(size 1.27 1.27)
				)
				(justify mirror)
			)
		)
		(duplicate_pad_numbers_are_jumpers no)
		(fp_poly
			(pts
				(xy -0.3048 -0.1016) (xy -0.3048 0.9906) (xy 0.3048 0.9906) (xy 0.3048 -0.1016)
			)
			(stroke
				(width 0)
				(type default)
			)
			(fill no)
			(layer "B.CrtYd")
		)
		(fp_line
			(start -0.3048 0.9906)
			(end -0.3048 -0.1016)
			(stroke
				(width 0.1)
				(type default)
			)
			(layer "B.Fab")
		)
		(fp_line
			(start 0.3048 0.9906)
			(end -0.3048 0.9906)
			(stroke
				(width 0.1)
				(type default)
			)
			(layer "B.Fab")
		)
		(fp_line
			(start -0.3048 -0.1016)
			(end 0.3048 -0.1016)
			(stroke
				(width 0.1)
				(type default)
			)
			(layer "B.Fab")
		)
		(fp_line
			(start 0.3048 -0.1016)
			(end 0.3048 0.9906)
			(stroke
				(width 0.1)
				(type default)
			)
			(layer "B.Fab")
		)
		(pad "1" smd rect
			(at 0 0 90)
			(size 0.508 0.508)
			(layers "B.Cu" "B.Mask" "B.Paste")
			(net "VCC_D_3V3")
		)
		(pad "2" smd rect
			(at 0 0.889 90)
			(size 0.508 0.508)
			(layers "B.Cu" "B.Mask" "B.Paste")
			(net "GND")
		)
		(zone
			(layer "B.Cu")
			(hatch none 0.5)
			(connect_pads
				(clearance 0)
			)
			(min_thickness 0.25)
			(keepout
				(tracks not_allowed)
				(vias allowed)
				(pads allowed)
				(copperpour not_allowed)
				(footprints allowed)
			)
			(placement
				(enabled no)
				(sheetname "")
			)
			(fill
				(thermal_gap 0.5)
				(thermal_bridge_width 0.5)
				(island_removal_mode 0)
			)
			(polygon
				(pts
					(xy 414.11652 -45.322744) (xy 414.11652 -45.830744) (xy 414.49752 -45.830744) (xy 414.49752 -45.322744)
				)
			)
		)
		(zone
			(layer "B.Cu")
			(hatch none 0.5)
			(connect_pads
				(clearance 0)
			)
			(min_thickness 0.25)
			(keepout
				(tracks allowed)
				(vias not_allowed)
				(pads allowed)
				(copperpour not_allowed)
				(footprints allowed)
			)
			(placement
				(enabled no)
				(sheetname "")
			)
			(fill
				(thermal_gap 0.5)
				(thermal_bridge_width 0.5)
				(island_removal_mode 0)
			)
			(polygon
				(pts
					(xy 414.49752 -45.322744) (xy 414.49752 -45.830744) (xy 414.11652 -45.830744) (xy 414.11652 -45.322744)
				)
			)
		)
	)
	(footprint ""
		(layer "B.Cu")
		(at 351.2312 -85.9536 90)
		(property "Reference" "C3P2"
			(at 0 0 90)
			(layer "B.SilkS")
			(hide yes)
			(effects
				(font
					(size 1.27 1.27)
				)
				(justify mirror)
			)
		)
		(property "Value" ""
			(at 0 0 90)
			(layer "B.Fab")
			(effects
				(font
					(size 1.27 1.27)
				)
				(justify mirror)
			)
		)
		(duplicate_pad_numbers_are_jumpers no)
		(fp_poly
			(pts
				(xy -0.3048 -0.1016) (xy -0.3048 0.9906) (xy 0.3048 0.9906) (xy 0.3048 -0.1016)
			)
			(stroke
				(width 0)
				(type default)
			)
			(fill no)
			(layer "B.CrtYd")
		)
		(fp_line
			(start 0.3048 -0.1016)
			(end 0.3048 0.9906)
			(stroke
				(width 0.1)
				(type default)
			)
			(layer "B.Fab")
		)
		(fp_line
			(start -0.3048 -0.1016)
			(end 0.3048 -0.1016)
			(stroke
				(width 0.1)
				(type default)
			)
			(layer "B.Fab")
		)
		(fp_line
			(start 0.3048 0.9906)
			(end -0.3048 0.9906)
			(stroke
				(width 0.1)
				(type default)
			)
			(layer "B.Fab")
		)
		(fp_line
			(start -0.3048 0.9906)
			(end -0.3048 -0.1016)
			(stroke
				(width 0.1)
				(type default)
			)
			(layer "B.Fab")
		)
		(pad "1" smd rect
			(at 0 0 270)
			(size 0.508 0.508)
			(layers "B.Cu" "B.Mask" "B.Paste")
			(net "VR_PVCCIO_CPU0_VINSEN")
		)
		(pad "2" smd rect
			(at 0 0.889 270)
			(size 0.508 0.508)
			(layers "B.Cu" "B.Mask" "B.Paste")
			(net "GND")
		)
		(zone
			(layer "B.Cu")
			(hatch none 0.5)
			(connect_pads
				(clearance 0)
			)
			(min_thickness 0.25)
			(keepout
				(tracks allowed)
				(vias not_allowed)
				(pads allowed)
				(copperpour not_allowed)
				(footprints allowed)
			)
			(placement
				(enabled no)
				(sheetname "")
			)
			(fill
				(thermal_gap 0.5)
				(thermal_bridge_width 0.5)
				(island_removal_mode 0)
			)
			(polygon
				(pts
					(xy 351.4852 -86.2076) (xy 351.4852 -85.6996) (xy 351.8662 -85.6996) (xy 351.8662 -86.2076)
				)
			)
		)
		(zone
			(layer "B.Cu")
			(hatch none 0.5)
			(connect_pads
				(clearance 0)
			)
			(min_thickness 0.25)
			(keepout
				(tracks not_allowed)
				(vias allowed)
				(pads allowed)
				(copperpour not_allowed)
				(footprints allowed)
			)
			(placement
				(enabled no)
				(sheetname "")
			)
			(fill
				(thermal_gap 0.5)
				(thermal_bridge_width 0.5)
				(island_removal_mode 0)
			)
			(polygon
				(pts
					(xy 351.8662 -86.2076) (xy 351.8662 -85.6996) (xy 351.4852 -85.6996) (xy 351.4852 -86.2076)
				)
			)
		)
	)
	(footprint ""
		(layer "B.Cu")
		(at 49.5808 -98.1202)
		(property "Reference" "R9N4"
			(at 0 0 0)
			(layer "B.SilkS")
			(hide yes)
			(effects
				(font
					(size 1.27 1.27)
				)
				(justify mirror)
			)
		)
		(property "Value" ""
			(at 0 0 0)
			(layer "B.Fab")
			(effects
				(font
					(size 1.27 1.27)
				)
				(justify mirror)
			)
		)
		(duplicate_pad_numbers_are_jumpers no)
		(fp_poly
			(pts
				(xy 0.2794 -0.1016) (xy -0.2794 -0.1016) (xy -0.2794 0.9906) (xy 0.2794 0.9906)
			)
			(stroke
				(width 0)
				(type default)
			)
			(fill no)
			(layer "B.CrtYd")
		)
		(fp_line
			(start -0.2794 -0.1016)
			(end 0.2794 -0.1016)
			(stroke
				(width 0.1)
				(type default)
			)
			(layer "B.Fab")
		)
		(fp_line
			(start -0.2794 0.9906)
			(end -0.2794 -0.1016)
			(stroke
				(width 0.1)
				(type default)
			)
			(layer "B.Fab")
		)
		(fp_line
			(start 0.2794 -0.1016)
			(end 0.2794 0.9906)
			(stroke
				(width 0.1)
				(type default)
			)
			(layer "B.Fab")
		)
		(fp_line
			(start 0.2794 0.9906)
			(end -0.2794 0.9906)
			(stroke
				(width 0.1)
				(type default)
			)
			(layer "B.Fab")
		)
		(pad "1" smd rect
			(at 0 0 180)
			(size 0.508 0.508)
			(layers "B.Cu" "B.Mask" "B.Paste")
			(net "PVSA_CPU1")
		)
		(pad "2" smd rect
			(at 0 0.889 180)
			(size 0.508 0.508)
			(layers "B.Cu" "B.Mask" "B.Paste")
			(net "GND")
		)
		(zone
			(layer "B.Cu")
			(hatch none 0.5)
			(connect_pads
				(clearance 0)
			)
			(min_thickness 0.25)
			(keepout
				(tracks allowed)
				(vias not_allowed)
				(pads allowed)
				(copperpour not_allowed)
				(footprints allowed)
			)
			(placement
				(enabled no)
				(sheetname "")
			)
			(fill
				(thermal_gap 0.5)
				(thermal_bridge_width 0.5)
				(island_removal_mode 0)
			)
			(polygon
				(pts
					(xy 49.8348 -97.8662) (xy 49.3268 -97.8662) (xy 49.3268 -97.4852) (xy 49.8348 -97.4852)
				)
			)
		)
		(zone
			(layer "B.Cu")
			(hatch none 0.5)
			(connect_pads
				(clearance 0)
			)
			(min_thickness 0.25)
			(keepout
				(tracks not_allowed)
				(vias allowed)
				(pads allowed)
				(copperpour not_allowed)
				(footprints allowed)
			)
			(placement
				(enabled no)
				(sheetname "")
			)
			(fill
				(thermal_gap 0.5)
				(thermal_bridge_width 0.5)
				(island_removal_mode 0)
			)
			(polygon
				(pts
					(xy 49.8348 -97.4852) (xy 49.3268 -97.4852) (xy 49.3268 -97.8662) (xy 49.8348 -97.8662)
				)
			)
		)
	)
)
